(kicad_pcb
	(version 20221018)
	(generator pcbnew)
	(general
    (thickness 1.7403)
  )
	(paper "A4")
	(title_block
    (title "Data Center RDIMM DDR4 Tester")
    (date "2024-09-30")
    (rev "1.2.4")
		(comment 9 "footprints 476-484 of 690")
	)
	(layers
    (0 "F.Cu" signal)
    (1 "In1.Cu" power)
    (2 "In2.Cu" signal)
    (3 "In3.Cu" power)
    (4 "In4.Cu" power)
    (5 "In5.Cu" signal)
    (6 "In6.Cu" power)
    (7 "In7.Cu" signal)
    (8 "In8.Cu" power)
    (9 "In9.Cu" signal)
    (10 "In10.Cu" power)
    (31 "B.Cu" signal)
    (32 "B.Adhes" user "B.Adhesive")
    (33 "F.Adhes" user "F.Adhesive")
    (34 "B.Paste" user)
    (35 "F.Paste" user)
    (36 "B.SilkS" user "B.Silkscreen")
    (37 "F.SilkS" user "F.Silkscreen")
    (38 "B.Mask" user)
    (39 "F.Mask" user)
    (40 "Dwgs.User" user "User.Drawings")
    (41 "Cmts.User" user "User.Comments")
    (42 "Eco1.User" user "User.Eco1")
    (43 "Eco2.User" user "User.Eco2")
    (44 "Edge.Cuts" user)
    (45 "Margin" user)
    (46 "B.CrtYd" user "B.Courtyard")
    (47 "F.CrtYd" user "F.Courtyard")
    (48 "B.Fab" user)
    (49 "F.Fab" user)
  )
	(footprint "data-center-rdimm-ddr4-tester-footprints:C_0201" (layer "B.Cu")
    (at 193.311328 79.285008 90)
    (descr "Capacitor SMD 0201")
    (tags "capacitor SMD 0201")
    (property "Author" "Antmicro")
    (property "Dielectric" "")
    (property "License" "Apache-2.0")
    (property "MPN" "CC0201KRX6S5BB104")
    (property "Manufacturer" "Yaego")
    (property "Sheetfile" "fpga-power.kicad_sch")
    (property "Sheetname" "FPGA power")
    (property "Val" "100n")
    (property "Voltage" "")
    (property "ki_description" " ")
    (attr smd)
    (fp_text reference "C71" (at 4.075008 0.688672 270) (layer "B.SilkS")
        (effects (font (size 0.7 0.7) (thickness 0.15)) (justify left bottom mirror))
    )
    (fp_text value "C_100n_0201" (at 0 -1.4 270) (layer "B.Fab") hide
        (effects (font (size 0.7 0.7) (thickness 0.15)) (justify left bottom mirror))
    )
    (fp_text user "${REFERENCE}" (at -0.72 -3.4 270) (layer "B.Fab") hide
        (effects (font (size 0.7 0.7) (thickness 0.15)) (justify left bottom mirror))
    )
    (fp_text user "License: Apache-2.0" (at -0.72 -4.4 270) (layer "B.Fab") hide
        (effects (font (size 0.7 0.7) (thickness 0.15)) (justify left bottom mirror))
    )
    (fp_text user "Author: Antmicro" (at -0.72 -5.4 270) (layer "B.Fab") hide
        (effects (font (size 0.7 0.7) (thickness 0.15)) (justify left bottom mirror))
    )
    (fp_rect (start -0.72 0.38) (end 0.72 -0.38)
      (stroke (width 0.05) (type solid)) (fill none) (layer "B.CrtYd"))
    (fp_rect (start 0.3 -0.15) (end -0.301 0.149)
      (stroke (width 0.15) (type solid)) (fill none) (layer "B.Fab"))
    (pad "" smd roundrect (at -0.349 0.002 90) (size 0.318 0.36) (layers "B.Paste") (roundrect_rratio 0.25))
    (pad "" smd roundrect (at 0.341 0.002 90) (size 0.318 0.36) (layers "B.Paste") (roundrect_rratio 0.25))
    (pad "1" smd roundrect (at -0.321 0.002 90) (size 0.46 0.4) (layers "B.Cu" "B.Mask") (roundrect_rratio 0.25)
      (net 77 "VDDQ") (pintype "passive"))
    (pad "2" smd roundrect (at 0.32 0.002 90) (size 0.46 0.4) (layers "B.Cu" "B.Mask") (roundrect_rratio 0.25)
      (net 9 "GND") (pintype "passive"))
  )
	(footprint "data-center-rdimm-ddr4-tester-footprints:C_0201" (layer "B.Cu")
    (at 190.886328 83.060008 90)
    (descr "Capacitor SMD 0201")
    (tags "capacitor SMD 0201")
    (property "Author" "Antmicro")
    (property "Dielectric" "")
    (property "License" "Apache-2.0")
    (property "MPN" "CC0201KRX6S5BB104")
    (property "Manufacturer" "Yaego")
    (property "Sheetfile" "fpga-power.kicad_sch")
    (property "Sheetname" "FPGA power")
    (property "Val" "100n")
    (property "Voltage" "")
    (property "ki_description" " ")
    (attr smd)
    (fp_text reference "C72" (at 1.060008 1.233672 270) (layer "B.SilkS")
        (effects (font (size 0.7 0.7) (thickness 0.15)) (justify left bottom mirror))
    )
    (fp_text value "C_100n_0201" (at 0 -1.4 270) (layer "B.Fab") hide
        (effects (font (size 0.7 0.7) (thickness 0.15)) (justify left bottom mirror))
    )
    (fp_text user "${REFERENCE}" (at -0.72 -3.4 270) (layer "B.Fab") hide
        (effects (font (size 0.7 0.7) (thickness 0.15)) (justify left bottom mirror))
    )
    (fp_text user "License: Apache-2.0" (at -0.72 -4.4 270) (layer "B.Fab") hide
        (effects (font (size 0.7 0.7) (thickness 0.15)) (justify left bottom mirror))
    )
    (fp_text user "Author: Antmicro" (at -0.72 -5.4 270) (layer "B.Fab") hide
        (effects (font (size 0.7 0.7) (thickness 0.15)) (justify left bottom mirror))
    )
    (fp_rect (start -0.72 0.38) (end 0.72 -0.38)
      (stroke (width 0.05) (type solid)) (fill none) (layer "B.CrtYd"))
    (fp_rect (start 0.3 -0.15) (end -0.301 0.149)
      (stroke (width 0.15) (type solid)) (fill none) (layer "B.Fab"))
    (pad "" smd roundrect (at -0.349 0.002 90) (size 0.318 0.36) (layers "B.Paste") (roundrect_rratio 0.25))
    (pad "" smd roundrect (at 0.341 0.002 90) (size 0.318 0.36) (layers "B.Paste") (roundrect_rratio 0.25))
    (pad "1" smd roundrect (at -0.321 0.002 90) (size 0.46 0.4) (layers "B.Cu" "B.Mask") (roundrect_rratio 0.25)
      (net 77 "VDDQ") (pintype "passive"))
    (pad "2" smd roundrect (at 0.32 0.002 90) (size 0.46 0.4) (layers "B.Cu" "B.Mask") (roundrect_rratio 0.25)
      (net 9 "GND") (pintype "passive"))
  )
	(footprint "data-center-rdimm-ddr4-tester-footprints:C_0201" (layer "B.Cu")
    (at 179.275 80.075 90)
    (descr "Capacitor SMD 0201")
    (tags "capacitor SMD 0201")
    (property "Author" "Antmicro")
    (property "Dielectric" "")
    (property "License" "Apache-2.0")
    (property "MPN" "CC0201KRX6S5BB104")
    (property "Manufacturer" "Yaego")
    (property "Sheetfile" "fpga-power.kicad_sch")
    (property "Sheetname" "FPGA power")
    (property "Val" "100n")
    (property "Voltage" "")
    (property "ki_description" " ")
    (attr smd)
    (fp_text reference "C73" (at 1.035 -0.365 270) (layer "B.SilkS")
        (effects (font (size 0.7 0.7) (thickness 0.15)) (justify left bottom mirror))
    )
    (fp_text value "C_100n_0201" (at 0 -1.4 270) (layer "B.Fab") hide
        (effects (font (size 0.7 0.7) (thickness 0.15)) (justify left bottom mirror))
    )
    (fp_text user "License: Apache-2.0" (at -0.72 -4.4 270) (layer "B.Fab") hide
        (effects (font (size 0.7 0.7) (thickness 0.15)) (justify left bottom mirror))
    )
    (fp_text user "${REFERENCE}" (at -0.72 -3.4 270) (layer "B.Fab") hide
        (effects (font (size 0.7 0.7) (thickness 0.15)) (justify left bottom mirror))
    )
    (fp_text user "Author: Antmicro" (at -0.72 -5.4 270) (layer "B.Fab") hide
        (effects (font (size 0.7 0.7) (thickness 0.15)) (justify left bottom mirror))
    )
    (fp_rect (start -0.72 0.38) (end 0.72 -0.38)
      (stroke (width 0.05) (type solid)) (fill none) (layer "B.CrtYd"))
    (fp_rect (start 0.3 -0.15) (end -0.301 0.149)
      (stroke (width 0.15) (type solid)) (fill none) (layer "B.Fab"))
    (pad "" smd roundrect (at -0.349 0.002 90) (size 0.318 0.36) (layers "B.Paste") (roundrect_rratio 0.25))
    (pad "" smd roundrect (at 0.341 0.002 90) (size 0.318 0.36) (layers "B.Paste") (roundrect_rratio 0.25))
    (pad "1" smd roundrect (at -0.321 0.002 90) (size 0.46 0.4) (layers "B.Cu" "B.Mask") (roundrect_rratio 0.25)
      (net 77 "VDDQ") (pintype "passive"))
    (pad "2" smd roundrect (at 0.32 0.002 90) (size 0.46 0.4) (layers "B.Cu" "B.Mask") (roundrect_rratio 0.25)
      (net 9 "GND") (pintype "passive"))
  )
	(footprint "data-center-rdimm-ddr4-tester-footprints:C_0201" (layer "B.Cu")
    (at 192.5 77.6)
    (descr "Capacitor SMD 0201")
    (tags "capacitor SMD 0201")
    (property "Author" "Antmicro")
    (property "Dielectric" "")
    (property "License" "Apache-2.0")
    (property "MPN" "CC0201KRX6S5BB104")
    (property "Manufacturer" "Yaego")
    (property "Sheetfile" "fpga-power.kicad_sch")
    (property "Sheetname" "FPGA power")
    (property "Val" "100n")
    (property "Voltage" "")
    (property "ki_description" " ")
    (attr smd)
    (fp_text reference "C75" (at 0.51 1.11 180) (layer "B.SilkS")
        (effects (font (size 0.7 0.7) (thickness 0.15)) (justify left bottom mirror))
    )
    (fp_text value "C_100n_0201" (at 0 -1.4 180) (layer "B.Fab") hide
        (effects (font (size 0.7 0.7) (thickness 0.15)) (justify left bottom mirror))
    )
    (fp_text user "License: Apache-2.0" (at -0.72 -4.4 180) (layer "B.Fab") hide
        (effects (font (size 0.7 0.7) (thickness 0.15)) (justify left bottom mirror))
    )
    (fp_text user "Author: Antmicro" (at -0.72 -5.4 180) (layer "B.Fab") hide
        (effects (font (size 0.7 0.7) (thickness 0.15)) (justify left bottom mirror))
    )
    (fp_text user "${REFERENCE}" (at -0.72 -3.4 180) (layer "B.Fab") hide
        (effects (font (size 0.7 0.7) (thickness 0.15)) (justify left bottom mirror))
    )
    (fp_rect (start -0.72 0.38) (end 0.72 -0.38)
      (stroke (width 0.05) (type solid)) (fill none) (layer "B.CrtYd"))
    (fp_rect (start 0.3 -0.15) (end -0.301 0.149)
      (stroke (width 0.15) (type solid)) (fill none) (layer "B.Fab"))
    (pad "" smd roundrect (at -0.349 0.002) (size 0.318 0.36) (layers "B.Paste") (roundrect_rratio 0.25))
    (pad "" smd roundrect (at 0.341 0.002) (size 0.318 0.36) (layers "B.Paste") (roundrect_rratio 0.25))
    (pad "1" smd roundrect (at -0.321 0.002) (size 0.46 0.4) (layers "B.Cu" "B.Mask") (roundrect_rratio 0.25)
      (net 77 "VDDQ") (pintype "passive"))
    (pad "2" smd roundrect (at 0.32 0.002) (size 0.46 0.4) (layers "B.Cu" "B.Mask") (roundrect_rratio 0.25)
      (net 9 "GND") (pintype "passive"))
  )
	(footprint "data-center-rdimm-ddr4-tester-footprints:C_0201" (layer "B.Cu")
    (at 194.2 82.05 90)
    (descr "Capacitor SMD 0201")
    (tags "capacitor SMD 0201")
    (property "Author" "Antmicro")
    (property "Dielectric" "")
    (property "License" "Apache-2.0")
    (property "MPN" "CC0201KRX6S5BB104")
    (property "Manufacturer" "Yaego")
    (property "Sheetfile" "fpga-power.kicad_sch")
    (property "Sheetname" "FPGA power")
    (property "Val" "100n")
    (property "Voltage" "")
    (property "ki_description" " ")
    (attr smd)
    (fp_text reference "C76" (at 1.18 -0.33 270) (layer "B.SilkS")
        (effects (font (size 0.7 0.7) (thickness 0.15)) (justify left bottom mirror))
    )
    (fp_text value "C_100n_0201" (at 0 -1.4 270) (layer "B.Fab") hide
        (effects (font (size 0.7 0.7) (thickness 0.15)) (justify left bottom mirror))
    )
    (fp_text user "License: Apache-2.0" (at -0.72 -4.4 270) (layer "B.Fab") hide
        (effects (font (size 0.7 0.7) (thickness 0.15)) (justify left bottom mirror))
    )
    (fp_text user "${REFERENCE}" (at -0.72 -3.4 270) (layer "B.Fab") hide
        (effects (font (size 0.7 0.7) (thickness 0.15)) (justify left bottom mirror))
    )
    (fp_text user "Author: Antmicro" (at -0.72 -5.4 270) (layer "B.Fab") hide
        (effects (font (size 0.7 0.7) (thickness 0.15)) (justify left bottom mirror))
    )
    (fp_rect (start -0.72 0.38) (end 0.72 -0.38)
      (stroke (width 0.05) (type solid)) (fill none) (layer "B.CrtYd"))
    (fp_rect (start 0.3 -0.15) (end -0.301 0.149)
      (stroke (width 0.15) (type solid)) (fill none) (layer "B.Fab"))
    (pad "" smd roundrect (at -0.349 0.002 90) (size 0.318 0.36) (layers "B.Paste") (roundrect_rratio 0.25))
    (pad "" smd roundrect (at 0.341 0.002 90) (size 0.318 0.36) (layers "B.Paste") (roundrect_rratio 0.25))
    (pad "1" smd roundrect (at -0.321 0.002 90) (size 0.46 0.4) (layers "B.Cu" "B.Mask") (roundrect_rratio 0.25)
      (net 77 "VDDQ") (pintype "passive"))
    (pad "2" smd roundrect (at 0.32 0.002 90) (size 0.46 0.4) (layers "B.Cu" "B.Mask") (roundrect_rratio 0.25)
      (net 9 "GND") (pintype "passive"))
  )
	(footprint "data-center-rdimm-ddr4-tester-footprints:C_0201" (layer "B.Cu")
    (at 196 83.05 -90)
    (descr "Capacitor SMD 0201")
    (tags "capacitor SMD 0201")
    (property "Author" "Antmicro")
    (property "Dielectric" "")
    (property "License" "Apache-2.0")
    (property "MPN" "CC0201KRX6S5BB104")
    (property "Manufacturer" "Yaego")
    (property "Sheetfile" "fpga-power.kicad_sch")
    (property "Sheetname" "FPGA power")
    (property "Val" "100n")
    (property "Voltage" "")
    (property "ki_description" " ")
    (attr smd)
    (fp_text reference "C143" (at -1.48 0.36 90) (layer "B.SilkS")
        (effects (font (size 0.7 0.7) (thickness 0.15)) (justify left bottom mirror))
    )
    (fp_text value "C_100n_0201" (at 0 -1.4 90) (layer "B.Fab") hide
        (effects (font (size 0.7 0.7) (thickness 0.15)) (justify left bottom mirror))
    )
    (fp_text user "${REFERENCE}" (at -0.72 -3.4 90) (layer "B.Fab") hide
        (effects (font (size 0.7 0.7) (thickness 0.15)) (justify left bottom mirror))
    )
    (fp_text user "License: Apache-2.0" (at -0.72 -4.4 90) (layer "B.Fab") hide
        (effects (font (size 0.7 0.7) (thickness 0.15)) (justify left bottom mirror))
    )
    (fp_text user "Author: Antmicro" (at -0.72 -5.4 90) (layer "B.Fab") hide
        (effects (font (size 0.7 0.7) (thickness 0.15)) (justify left bottom mirror))
    )
    (fp_rect (start -0.72 0.38) (end 0.72 -0.38)
      (stroke (width 0.05) (type solid)) (fill none) (layer "B.CrtYd"))
    (fp_rect (start 0.3 -0.15) (end -0.301 0.149)
      (stroke (width 0.15) (type solid)) (fill none) (layer "B.Fab"))
    (pad "" smd roundrect (at -0.349 0.002 270) (size 0.318 0.36) (layers "B.Paste") (roundrect_rratio 0.25))
    (pad "" smd roundrect (at 0.341 0.002 270) (size 0.318 0.36) (layers "B.Paste") (roundrect_rratio 0.25))
    (pad "1" smd roundrect (at -0.321 0.002 270) (size 0.46 0.4) (layers "B.Cu" "B.Mask") (roundrect_rratio 0.25)
      (net 77 "VDDQ") (pintype "passive"))
    (pad "2" smd roundrect (at 0.32 0.002 270) (size 0.46 0.4) (layers "B.Cu" "B.Mask") (roundrect_rratio 0.25)
      (net 9 "GND") (pintype "passive"))
  )
	(footprint "data-center-rdimm-ddr4-tester-footprints:R_0402_1005Metric" (layer "B.Cu")
    (at 160.686328 87.120008 90)
    (descr "Resistor SMD 0402")
    (tags "resistor SMD 0402")
    (property "Author" "Antmicro")
    (property "License" "Apache-2.0")
    (property "MPN" "CR0402-FX-1002GLF")
    (property "Manufacturer" "Bourns")
    (property "Sheetfile" "ethernet.kicad_sch")
    (property "Sheetname" "Ethernet")
    (property "Tolerance" "1%")
    (property "Val" "10k")
    (property "ki_description" "10k resistor in 0402 package with 1% tolerance")
    (attr smd)
    (fp_text reference "R73" (at 1.170008 8.103672 270) (layer "B.SilkS")
        (effects (font (size 0.7 0.7) (thickness 0.15)) (justify left bottom mirror))
    )
    (fp_text value "R_10k_0402" (at 0 -1.4 270) (layer "B.Fab") hide
        (effects (font (size 0.7 0.7) (thickness 0.15)) (justify left bottom mirror))
    )
    (fp_text user "Author: Antmicro" (at -0.95 -4.169 270) (layer "B.Fab") hide
        (effects (font (size 0.7 0.7) (thickness 0.15)) (justify left bottom mirror))
    )
    (fp_text user "${REFERENCE}" (at -0.95 -3.168 270) (layer "B.Fab") hide
        (effects (font (size 0.7 0.7) (thickness 0.15)) (justify left bottom mirror))
    )
    (fp_text user "License: Apache-2.0" (at -0.95 -5.169 270) (layer "B.Fab") hide
        (effects (font (size 0.7 0.7) (thickness 0.15)) (justify left bottom mirror))
    )
    (fp_rect (start -0.93 0.47) (end 0.93 -0.47)
      (stroke (width 0.05) (type solid)) (fill none) (layer "B.CrtYd"))
    (fp_rect (start -0.5 0.25) (end 0.5 -0.25)
      (stroke (width 0.15) (type solid)) (fill none) (layer "B.Fab"))
    (pad "1" smd roundrect (at -0.485 0 90) (size 0.59 0.64) (layers "B.Cu" "B.Paste" "B.Mask") (roundrect_rratio 0.25)
      (net 37 "ETH_RXD3") (pintype "passive"))
    (pad "2" smd roundrect (at 0.485 0 90) (size 0.59 0.64) (layers "B.Cu" "B.Paste" "B.Mask") (roundrect_rratio 0.25)
      (net 143 "3V3_SYS") (pintype "passive"))
  )
	(footprint "data-center-rdimm-ddr4-tester-footprints:R_0402_1005Metric" (layer "B.Cu")
    (at 160.736328 89.340008 -90)
    (descr "Resistor SMD 0402")
    (tags "resistor SMD 0402")
    (property "Author" "Antmicro")
    (property "DNP" "DNP")
    (property "License" "Apache-2.0")
    (property "MPN" "CR0402-FX-2201GLF")
    (property "Manufacturer" "Bourns")
    (property "Sheetfile" "ethernet.kicad_sch")
    (property "Sheetname" "Ethernet")
    (property "Tolerance" "1%")
    (property "Val" "2k2")
    (property "dnp" "")
    (property "exclude_from_bom" "")
    (property "ki_description" "2k2 resistor in 0402 package with 1% tolerance")
    (attr exclude_from_pos_files exclude_from_bom)
    (fp_text reference "R91" (at -1.165008 -7.958672 90) (layer "B.SilkS")
        (effects (font (size 0.7 0.7) (thickness 0.15)) (justify left bottom mirror))
    )
    (fp_text value "R_2k2_0402" (at 0 -1.4 90) (layer "B.Fab") hide
        (effects (font (size 0.7 0.7) (thickness 0.15)) (justify left bottom mirror))
    )
    (fp_text user "Author: Antmicro" (at -0.95 -4.169 90) (layer "B.Fab") hide
        (effects (font (size 0.7 0.7) (thickness 0.15)) (justify left bottom mirror))
    )
    (fp_text user "License: Apache-2.0" (at -0.95 -5.169 90) (layer "B.Fab") hide
        (effects (font (size 0.7 0.7) (thickness 0.15)) (justify left bottom mirror))
    )
    (fp_text user "${REFERENCE}" (at -0.95 -3.168 90) (layer "B.Fab") hide
        (effects (font (size 0.7 0.7) (thickness 0.15)) (justify left bottom mirror))
    )
    (fp_rect (start -0.93 0.47) (end 0.93 -0.47)
      (stroke (width 0.05) (type solid)) (fill none) (layer "B.CrtYd"))
    (fp_rect (start -0.5 0.25) (end 0.5 -0.25)
      (stroke (width 0.15) (type solid)) (fill none) (layer "B.Fab"))
    (pad "1" smd roundrect (at -0.485 0 270) (size 0.59 0.64) (layers "B.Cu" "B.Paste" "B.Mask") (roundrect_rratio 0.25)
      (net 37 "ETH_RXD3") (pintype "passive"))
    (pad "2" smd roundrect (at 0.485 0 270) (size 0.59 0.64) (layers "B.Cu" "B.Paste" "B.Mask") (roundrect_rratio 0.25)
      (net 9 "GND") (pintype "passive"))
  )
	(footprint "data-center-rdimm-ddr4-tester-footprints:C_0402_1005Metric" (layer "B.Cu")
    (at 186.136328 92.985008 90)
    (descr "Capacitor SMD 0402")
    (tags "capacitor SMD 0402")
    (property "Author" "Antmicro")
    (property "Dielectric" "")
    (property "License" "Apache-2.0")
    (property "MPN" "GRM155R61A475MEAAD")
    (property "Manufacturer" "Murata")
    (property "Sheetfile" "fpga-power.kicad_sch")
    (property "Sheetname" "FPGA power")
    (property "Val" "4u7")
    (property "Voltage" "")
    (property "ki_description" " ")
    (attr smd)
    (fp_text reference "C115" (at 10.625008 18.513672 270) (layer "B.SilkS")
        (effects (font (size 0.7 0.7) (thickness 0.15)) (justify left bottom mirror))
    )
    (fp_text value "C_4u7_0402" (at 0 -1.4 270) (layer "B.Fab") hide
        (effects (font (size 0.7 0.7) (thickness 0.15)) (justify left bottom mirror))
    )
    (fp_text user "License: Apache-2.0" (at -0.932 -5.17 270) (layer "B.Fab") hide
        (effects (font (size 0.7 0.7) (thickness 0.15)) (justify left bottom mirror))
    )
    (fp_text user "${REFERENCE}" (at -0.932 -3.168 270) (layer "B.Fab") hide
        (effects (font (size 0.7 0.7) (thickness 0.15)) (justify left bottom mirror))
    )
    (fp_text user "Author: Antmicro" (at -0.932 -4.17 270) (layer "B.Fab") hide
        (effects (font (size 0.7 0.7) (thickness 0.15)) (justify left bottom mirror))
    )
    (fp_rect (start -0.94 0.47) (end 0.94 -0.47)
      (stroke (width 0.05) (type solid)) (fill none) (layer "B.CrtYd"))
    (fp_rect (start -0.499 0.249) (end 0.499 -0.249)
      (stroke (width 0.15) (type solid)) (fill none) (layer "B.Fab"))
    (pad "1" smd roundrect (at -0.484 0 90) (size 0.59 0.64) (layers "B.Cu" "B.Paste" "B.Mask") (roundrect_rratio 0.25)
      (net 144 "1V8_SYS") (pintype "passive"))
    (pad "2" smd roundrect (at 0.484 0 90) (size 0.59 0.64) (layers "B.Cu" "B.Paste" "B.Mask") (roundrect_rratio 0.25)
      (net 9 "GND") (pintype "passive"))
  )
)
